(kicad_pcb
	(version 20260206)
	(generator "pcbnew")
	(generator_version "10.0")
	(general
		(thickness 1.6)
		(legacy_teardrops no)
	)
	(paper "A4")
	(title_block
		(title "04192023_DAF0TMB3IC0_F0TG_MB_C_brd_V02_OCP.brd")
		(comment 1 "Grand Teton / footprints 4690-4695 of 8354")
	)
	(layers
		(0 "F.Cu" signal "TOP")
		(4 "In1.Cu" signal "GND")
		(6 "In2.Cu" signal "IN1")
		(8 "In3.Cu" signal "GND1")
		(10 "In4.Cu" signal "IN2")
		(12 "In5.Cu" signal "GND2")
		(14 "In6.Cu" signal "IN3")
		(16 "In7.Cu" signal "GND3")
		(18 "In8.Cu" signal "VCC")
		(20 "In9.Cu" signal "VCC1")
		(22 "In10.Cu" signal "GND4")
		(24 "In11.Cu" signal "IN4")
		(26 "In12.Cu" signal "GND5")
		(28 "In13.Cu" signal "IN5")
		(30 "In14.Cu" signal "GND6")
		(32 "In15.Cu" signal "IN6")
		(34 "In16.Cu" signal "GND7")
		(2 "B.Cu" signal "BOTTOM")
		(9 "F.Adhes" user "F.Adhesive")
		(11 "B.Adhes" user "B.Adhesive")
		(13 "F.Paste" user "Package Geometry/Pastemask Top")
		(15 "B.Paste" user "Package Geometry/Pastemask Bottom")
		(5 "F.SilkS" user "Ref Des/Silkscreen Top")
		(7 "B.SilkS" user "Ref Des/Silkscreen Bottom")
		(1 "F.Mask" user "Board Geometry/Soldermask Top")
		(3 "B.Mask" user "Board Geometry/Soldermask Bottom")
		(17 "Dwgs.User" user "User.Drawings")
		(19 "Cmts.User" user "User.Comments")
		(21 "Eco1.User" user "User.Eco1")
		(23 "Eco2.User" user "User.Eco2")
		(25 "Edge.Cuts" user "Board Geometry/Outline")
		(27 "Margin" user)
		(31 "F.CrtYd" user "Package Geometry/Place Bound Top")
		(29 "B.CrtYd" user "Package Geometry/Place Bound Bottom")
		(35 "F.Fab" user "Ref Des/Assembly Top")
		(33 "B.Fab" user "Ref Des/Assembly Bottom")
	)
	(footprint ""
		(layer "F.Cu")
		(at 347.727778 -161.139378 180)
		(property "Reference" "PU10"
			(at 6.094476 -1.518666 0)
			(unlocked yes)
			(layer "F.SilkS")
			(effects
				(font
					(size 0.7874 0.5842)
					(thickness 0.1524)
				)
				(justify left)
			)
		)
		(property "Value" ""
			(at 0 0 180)
			(layer "F.Fab")
			(effects
				(font
					(size 1.27 1.27)
				)
			)
		)
		(duplicate_pad_numbers_are_jumpers no)
		(fp_line
			(start 2.500122 2.999994)
			(end 2.2987 2.999994)
			(stroke
				(width 0.1524)
				(type default)
			)
			(layer "F.SilkS")
		)
		(fp_line
			(start 2.500122 2.339594)
			(end 2.500122 2.999994)
			(stroke
				(width 0.1524)
				(type default)
			)
			(layer "F.SilkS")
		)
		(fp_line
			(start 2.500122 -2.999994)
			(end 2.500122 -2.44348)
			(stroke
				(width 0.1524)
				(type default)
			)
			(layer "F.SilkS")
		)
		(fp_line
			(start 2.31394 -2.999994)
			(end 2.500122 -2.999994)
			(stroke
				(width 0.1524)
				(type default)
			)
			(layer "F.SilkS")
		)
		(fp_line
			(start -2.2987 2.999994)
			(end -2.500122 2.999994)
			(stroke
				(width 0.1524)
				(type default)
			)
			(layer "F.SilkS")
		)
		(fp_line
			(start -2.500122 2.999994)
			(end -2.500122 2.339594)
			(stroke
				(width 0.1524)
				(type default)
			)
			(layer "F.SilkS")
		)
		(fp_line
			(start -2.500122 0.6604)
			(end -2.500122 0.229108)
			(stroke
				(width 0.1524)
				(type default)
			)
			(layer "F.SilkS")
		)
		(fp_line
			(start -2.500122 -2.529078)
			(end -2.500122 -2.999994)
			(stroke
				(width 0.1524)
				(type default)
			)
			(layer "F.SilkS")
		)
		(fp_line
			(start -2.500122 -2.999994)
			(end -2.24409 -2.999994)
			(stroke
				(width 0.1524)
				(type default)
			)
			(layer "F.SilkS")
		)
		(fp_poly
			(pts
				(xy -2.644902 -2.457196) (xy -3.412236 -2.712974) (xy -2.90068 -3.22453)
			)
			(stroke
				(width 0)
				(type default)
			)
			(fill yes)
			(layer "F.SilkS")
		)
		(fp_line
			(start 2.500122 2.999994)
			(end -2.500122 2.999994)
			(stroke
				(width 0.1)
				(type default)
			)
			(layer "F.Fab")
		)
		(fp_line
			(start 2.500122 -2.999994)
			(end 2.500122 2.999994)
			(stroke
				(width 0.1)
				(type default)
			)
			(layer "F.Fab")
		)
		(fp_line
			(start -2.500122 2.999994)
			(end -2.500122 -2.999994)
			(stroke
				(width 0.1)
				(type default)
			)
			(layer "F.Fab")
		)
		(fp_line
			(start -2.500122 -2.999994)
			(end 2.500122 -2.999994)
			(stroke
				(width 0.1)
				(type default)
			)
			(layer "F.Fab")
		)
		(fp_poly
			(pts
				(xy -4.218432 -2.783078) (xy -4.218432 -1.767078) (xy -3.202432 -2.275078)
			)
			(stroke
				(width 0)
				(type default)
			)
			(fill yes)
			(layer "F.Fab")
		)
		(pad "1" smd rect
			(at -2.400046 -2.275078 270)
			(size 0.2286 0.6096)
			(layers "F.Cu" "F.Mask" "F.Paste")
			(net "PVDDCR_CPU0_P0_VOS6")
		)
		(pad "2" smd rect
			(at -2.400046 -1.82499 270)
			(size 0.2286 0.6096)
			(layers "F.Cu" "F.Mask" "F.Paste")
			(net "GND")
		)
		(pad "3" smd rect
			(at -2.400046 -1.374902 270)
			(size 0.2286 0.6096)
			(layers "F.Cu" "F.Mask" "F.Paste")
			(net "PVDDCR_CPU0_P0_VCC6")
		)
		(pad "4" smd rect
			(at -2.400046 -0.925068 270)
			(size 0.2286 0.6096)
			(layers "F.Cu" "F.Mask" "F.Paste")
			(net "PVDDCR_CPU0_P0_PVCC")
		)
		(pad "5" smd rect
			(at -2.400046 -0.47498 270)
			(size 0.2286 0.6096)
			(layers "F.Cu" "F.Mask" "F.Paste")
			(net "GND")
		)
		(pad "6" smd rect
			(at -2.400046 -0.024892 270)
			(size 0.2286 0.6096)
			(layers "F.Cu" "F.Mask" "F.Paste")
			(net "NC_PVDDCR_CPU0_P0_GL1_6")
		)
		(pad "7_9-20_24" smd circle
			(at 0 1.150112 270)
			(size 0 0)
			(layers "F.Cu" "F.Mask" "F.Paste")
			(net "GND")
		)
		(pad "10_19" smd rect
			(at 0 2.899918 270)
			(size 0.6096 4.318)
			(layers "F.Cu" "F.Mask" "F.Paste")
			(net "SW_PVDDCR_CPU0_P0_SW6")
		)
		(pad "25_29" smd rect
			(at 1.549908 -1.279906 90)
			(size 2.0574 2.3114)
			(layers "F.Cu" "F.Mask" "F.Paste")
			(net "SW_P12V_AUX_PVDDCR_CPU0_P0_FLT")
		)
		(pad "30" smd rect
			(at 2.05994 -2.899918 180)
			(size 0.2286 0.6096)
			(layers "F.Cu" "F.Mask" "F.Paste")
			(net "SW_P12V_AUX_PVDDCR_CPU0_P0_FLT")
		)
		(pad "31" smd rect
			(at 1.610106 -2.899918 180)
			(size 0.2286 0.6096)
			(layers "F.Cu" "F.Mask" "F.Paste")
			(net "NC_PVDDCR_CPU0_P0_DNC6")
		)
		(pad "32" smd rect
			(at 1.160018 -2.899918 180)
			(size 0.2286 0.6096)
			(layers "F.Cu" "F.Mask" "F.Paste")
			(net "SW_PVDDCR_CPU0_P0_PH6")
		)
		(pad "33" smd rect
			(at 0.70993 -2.899918 180)
			(size 0.2286 0.6096)
			(layers "F.Cu" "F.Mask" "F.Paste")
			(net "SW_PVDDCR_CPU0_P0_BOOT6")
		)
		(pad "34" smd rect
			(at 0.260096 -2.899918 180)
			(size 0.2286 0.6096)
			(layers "F.Cu" "F.Mask" "F.Paste")
			(net "PVDDCR_CPU0_P0_PWM6")
		)
		(pad "35" smd rect
			(at -0.189992 -2.899918 180)
			(size 0.2286 0.6096)
			(layers "F.Cu" "F.Mask" "F.Paste")
			(net "PVDDCR_CPU0_P0_VCC6")
		)
		(pad "36" smd rect
			(at -0.64008 -2.899918 180)
			(size 0.2286 0.6096)
			(layers "F.Cu" "F.Mask" "F.Paste")
			(net "PVDDCR_CPU0_P0_TEMP0")
		)
		(pad "37" smd rect
			(at -1.089914 -2.899918 180)
			(size 0.2286 0.6096)
			(layers "F.Cu" "F.Mask" "F.Paste")
			(net "PVDDCR_CPU0_P0_LSET6")
		)
		(pad "38" smd rect
			(at -1.540002 -2.899918 180)
			(size 0.2286 0.6096)
			(layers "F.Cu" "F.Mask" "F.Paste")
			(net "PVDDCR_CPU0_P0_IMON6")
		)
		(pad "39" smd rect
			(at -1.99009 -2.899918 180)
			(size 0.2286 0.6096)
			(layers "F.Cu" "F.Mask" "F.Paste")
			(net "PVDDCR_CPU0_P0_VCCS")
		)
		(pad "40" smd rect
			(at -0.87503 -1.27508 180)
			(size 1.7526 1.9558)
			(layers "F.Cu" "F.Mask" "F.Paste")
			(net "GND")
		)
		(pad "41" smd rect
			(at -1.525016 0.249936 90)
			(size 0.3048 0.4572)
			(layers "F.Cu" "F.Mask" "F.Paste")
			(net "NC_PVDDCR_CPU0_P0_GL2_6")
		)
		(zone
			(layer "F.Cu")
			(hatch none 0.5)
			(connect_pads
				(clearance 0)
			)
			(min_thickness 0.25)
			(keepout
				(tracks not_allowed)
				(vias allowed)
				(pads allowed)
				(copperpour not_allowed)
				(footprints allowed)
			)
			(placement
				(enabled no)
				(sheetname "")
			)
			(fill
				(thermal_gap 0.5)
				(thermal_bridge_width 0.5)
				(island_removal_mode 0)
			)
			(polygon
				(pts
					(xy 350.2279 -163.726114) (xy 350.2279 -163.390072) (xy 345.227656 -163.390072) (xy 345.227656 -163.711128)
					(xy 345.517978 -163.711128) (xy 345.517978 -163.683696) (xy 349.937578 -163.683696) (xy 349.937578 -163.726114)
				)
			)
		)
		(zone
			(layer "F.Cu")
			(hatch none 0.5)
			(connect_pads
				(clearance 0)
			)
			(min_thickness 0.25)
			(keepout
				(tracks not_allowed)
				(vias allowed)
				(pads allowed)
				(copperpour not_allowed)
				(footprints allowed)
			)
			(placement
				(enabled no)
				(sheetname "")
			)
			(fill
				(thermal_gap 0.5)
				(thermal_bridge_width 0.5)
				(island_removal_mode 0)
			)
			(polygon
				(pts
					(xy 347.675708 -160.892998) (xy 347.675708 -158.835598) (xy 349.529908 -158.835598) (xy 349.529908 -159.076644)
					(xy 349.772224 -159.076644) (xy 349.772224 -158.59506) (xy 345.886024 -158.59506) (xy 345.886024 -158.779972)
					(xy 347.38437 -158.779972) (xy 347.38437 -160.938972) (xy 345.227656 -160.938972) (xy 345.227656 -161.188654)
					(xy 347.380052 -161.188654)
				)
			)
		)
	)
	(footprint ""
		(layer "F.Cu")
		(at 410.690822 -416.899344 -90)
		(property "Reference" "C6592"
			(at 0 0 270)
			(layer "F.SilkS")
			(hide yes)
			(effects
				(font
					(size 1.27 1.27)
				)
			)
		)
		(property "Value" ""
			(at 0 0 270)
			(layer "F.Fab")
			(effects
				(font
					(size 1.27 1.27)
				)
			)
		)
		(duplicate_pad_numbers_are_jumpers no)
		(fp_line
			(start -0.299974 0.150114)
			(end -0.299974 -0.150114)
			(stroke
				(width 0.1)
				(type default)
			)
			(layer "F.Fab")
		)
		(fp_line
			(start 0.299974 0.150114)
			(end -0.299974 0.150114)
			(stroke
				(width 0.1)
				(type default)
			)
			(layer "F.Fab")
		)
		(fp_line
			(start -0.299974 -0.150114)
			(end 0.299974 -0.150114)
			(stroke
				(width 0.1)
				(type default)
			)
			(layer "F.Fab")
		)
		(fp_line
			(start 0.299974 -0.150114)
			(end 0.299974 0.150114)
			(stroke
				(width 0.1)
				(type default)
			)
			(layer "F.Fab")
		)
		(pad "1" smd rect
			(at -0.2667 0 270)
			(size 0.3048 0.381)
			(layers "F.Cu" "F.Mask" "F.Paste")
			(net "P5E_CPU0_P2_TX_BUF_C_DN<13>")
		)
		(pad "2" smd rect
			(at 0.2667 0 270)
			(size 0.3048 0.381)
			(layers "F.Cu" "F.Mask" "F.Paste")
			(net "P5E_CPU0_P2_TX_BUF_DN<13>")
		)
	)
	(footprint ""
		(layer "F.Cu")
		(at 380.972822 -416.899344 -90)
		(property "Reference" "C6571"
			(at 0 0 270)
			(layer "F.SilkS")
			(hide yes)
			(effects
				(font
					(size 1.27 1.27)
				)
			)
		)
		(property "Value" ""
			(at 0 0 270)
			(layer "F.Fab")
			(effects
				(font
					(size 1.27 1.27)
				)
			)
		)
		(duplicate_pad_numbers_are_jumpers no)
		(fp_line
			(start -0.299974 0.150114)
			(end -0.299974 -0.150114)
			(stroke
				(width 0.1)
				(type default)
			)
			(layer "F.Fab")
		)
		(fp_line
			(start 0.299974 0.150114)
			(end -0.299974 0.150114)
			(stroke
				(width 0.1)
				(type default)
			)
			(layer "F.Fab")
		)
		(fp_line
			(start -0.299974 -0.150114)
			(end 0.299974 -0.150114)
			(stroke
				(width 0.1)
				(type default)
			)
			(layer "F.Fab")
		)
		(fp_line
			(start 0.299974 -0.150114)
			(end 0.299974 0.150114)
			(stroke
				(width 0.1)
				(type default)
			)
			(layer "F.Fab")
		)
		(pad "1" smd rect
			(at -0.2667 0 270)
			(size 0.3048 0.381)
			(layers "F.Cu" "F.Mask" "F.Paste")
			(net "P5E_CPU0_P2_TX_BUF_C_DP<3>")
		)
		(pad "2" smd rect
			(at 0.2667 0 270)
			(size 0.3048 0.381)
			(layers "F.Cu" "F.Mask" "F.Paste")
			(net "P5E_CPU0_P2_TX_BUF_DP<3>")
		)
	)
	(footprint ""
		(layer "F.Cu")
		(at 302.241458 -111.811308 180)
		(property "Reference" "R62"
			(at 0 0 180)
			(layer "F.SilkS")
			(hide yes)
			(effects
				(font
					(size 1.27 1.27)
				)
			)
		)
		(property "Value" ""
			(at 0 0 180)
			(layer "F.Fab")
			(effects
				(font
					(size 1.27 1.27)
				)
			)
		)
		(duplicate_pad_numbers_are_jumpers no)
		(fp_line
			(start 0.7874 0.4064)
			(end -0.7874 0.4064)
			(stroke
				(width 0.1524)
				(type default)
			)
			(layer "F.SilkS")
		)
		(fp_line
			(start 0.7874 -0.4064)
			(end 0.7874 0.4064)
			(stroke
				(width 0.1524)
				(type default)
			)
			(layer "F.SilkS")
		)
		(fp_line
			(start -0.7874 0.4064)
			(end -0.7874 -0.4064)
			(stroke
				(width 0.1524)
				(type default)
			)
			(layer "F.SilkS")
		)
		(fp_line
			(start -0.7874 -0.4064)
			(end 0.7874 -0.4064)
			(stroke
				(width 0.1524)
				(type default)
			)
			(layer "F.SilkS")
		)
		(fp_line
			(start 0.67945 0.3048)
			(end 0.120396 0.3048)
			(stroke
				(width 0.1)
				(type default)
			)
			(layer "F.Fab")
		)
		(fp_line
			(start 0.67945 -0.3048)
			(end 0.67945 0.3048)
			(stroke
				(width 0.1)
				(type default)
			)
			(layer "F.Fab")
		)
		(fp_line
			(start 0.12065 -0.2794)
			(end 0.12065 -0.3048)
			(stroke
				(width 0.1)
				(type default)
			)
			(layer "F.Fab")
		)
		(fp_line
			(start 0.12065 -0.3048)
			(end 0.67945 -0.3048)
			(stroke
				(width 0.1)
				(type default)
			)
			(layer "F.Fab")
		)
		(fp_line
			(start 0.120396 0.3048)
			(end 0.120396 0.2794)
			(stroke
				(width 0.1)
				(type default)
			)
			(layer "F.Fab")
		)
		(fp_line
			(start 0.120396 0.2794)
			(end -0.12065 0.2794)
			(stroke
				(width 0.1)
				(type default)
			)
			(layer "F.Fab")
		)
		(fp_line
			(start -0.12065 0.3048)
			(end -0.67945 0.3048)
			(stroke
				(width 0.1)
				(type default)
			)
			(layer "F.Fab")
		)
		(fp_line
			(start -0.12065 0.2794)
			(end -0.12065 0.3048)
			(stroke
				(width 0.1)
				(type default)
			)
			(layer "F.Fab")
		)
		(fp_line
			(start -0.12065 -0.2794)
			(end 0.12065 -0.2794)
			(stroke
				(width 0.1)
				(type default)
			)
			(layer "F.Fab")
		)
		(fp_line
			(start -0.12065 -0.305054)
			(end -0.12065 -0.2794)
			(stroke
				(width 0.1)
				(type default)
			)
			(layer "F.Fab")
		)
		(fp_line
			(start -0.67945 0.3048)
			(end -0.67945 -0.305054)
			(stroke
				(width 0.1)
				(type default)
			)
			(layer "F.Fab")
		)
		(fp_line
			(start -0.67945 -0.305054)
			(end -0.12065 -0.305054)
			(stroke
				(width 0.1)
				(type default)
			)
			(layer "F.Fab")
		)
		(pad "1" smd circle
			(at -0.40005 0 180)
			(size 0 0)
			(layers "F.Cu" "F.Mask" "F.Paste")
			(net "CPU_FRU_ADDR1")
		)
		(pad "2" smd circle
			(at 0.40005 0 180)
			(size 0 0)
			(layers "F.Cu" "F.Mask" "F.Paste")
			(net "GND")
		)
	)
	(footprint ""
		(layer "F.Cu")
		(at 367.787936 -403.818852 -90)
		(property "Reference" "R1107"
			(at 0 0 270)
			(layer "F.SilkS")
			(hide yes)
			(effects
				(font
					(size 1.27 1.27)
				)
			)
		)
		(property "Value" ""
			(at 0 0 270)
			(layer "F.Fab")
			(effects
				(font
					(size 1.27 1.27)
				)
			)
		)
		(duplicate_pad_numbers_are_jumpers no)
		(fp_line
			(start -0.32512 0.175006)
			(end -0.32512 -0.175006)
			(stroke
				(width 0.1)
				(type default)
			)
			(layer "F.Fab")
		)
		(fp_line
			(start 0.32512 0.175006)
			(end -0.32512 0.175006)
			(stroke
				(width 0.1)
				(type default)
			)
			(layer "F.Fab")
		)
		(fp_line
			(start -0.32512 -0.175006)
			(end 0.32512 -0.175006)
			(stroke
				(width 0.1)
				(type default)
			)
			(layer "F.Fab")
		)
		(fp_line
			(start 0.32512 -0.175006)
			(end 0.32512 0.175006)
			(stroke
				(width 0.1)
				(type default)
			)
			(layer "F.Fab")
		)
		(pad "1" smd rect
			(at -0.2667 0 270)
			(size 0.3048 0.381)
			(layers "F.Cu" "F.Mask" "F.Paste")
			(net "P1V8_CPU0_RT_1D")
		)
		(pad "2" smd rect
			(at 0.2667 0 90)
			(size 0.3048 0.381)
			(layers "F.Cu" "F.Mask" "F.Paste")
			(net "RST_RT_CPU0_P3_RESET_R_N")
		)
	)
	(footprint ""
		(layer "F.Cu")
		(at 66.47434 -52.74564)
		(property "Reference" "R1524"
			(at 0 0 0)
			(layer "F.SilkS")
			(hide yes)
			(effects
				(font
					(size 1.27 1.27)
				)
			)
		)
		(property "Value" ""
			(at 0 0 0)
			(layer "F.Fab")
			(effects
				(font
					(size 1.27 1.27)
				)
			)
		)
		(duplicate_pad_numbers_are_jumpers no)
		(fp_line
			(start -0.7874 -0.4064)
			(end 0.7874 -0.4064)
			(stroke
				(width 0.1524)
				(type default)
			)
			(layer "F.SilkS")
		)
		(fp_line
			(start -0.7874 0.4064)
			(end -0.7874 -0.4064)
			(stroke
				(width 0.1524)
				(type default)
			)
			(layer "F.SilkS")
		)
		(fp_line
			(start 0.7874 -0.4064)
			(end 0.7874 0.4064)
			(stroke
				(width 0.1524)
				(type default)
			)
			(layer "F.SilkS")
		)
		(fp_line
			(start 0.7874 0.4064)
			(end -0.7874 0.4064)
			(stroke
				(width 0.1524)
				(type default)
			)
			(layer "F.SilkS")
		)
		(fp_line
			(start -0.67945 -0.305054)
			(end -0.12065 -0.305054)
			(stroke
				(width 0.1)
				(type default)
			)
			(layer "F.Fab")
		)
		(fp_line
			(start -0.67945 0.3048)
			(end -0.67945 -0.305054)
			(stroke
				(width 0.1)
				(type default)
			)
			(layer "F.Fab")
		)
		(fp_line
			(start -0.12065 -0.305054)
			(end -0.12065 -0.2794)
			(stroke
				(width 0.1)
				(type default)
			)
			(layer "F.Fab")
		)
		(fp_line
			(start -0.12065 -0.2794)
			(end 0.12065 -0.2794)
			(stroke
				(width 0.1)
				(type default)
			)
			(layer "F.Fab")
		)
		(fp_line
			(start -0.12065 0.2794)
			(end -0.12065 0.3048)
			(stroke
				(width 0.1)
				(type default)
			)
			(layer "F.Fab")
		)
		(fp_line
			(start -0.12065 0.3048)
			(end -0.67945 0.3048)
			(stroke
				(width 0.1)
				(type default)
			)
			(layer "F.Fab")
		)
		(fp_line
			(start 0.120396 0.2794)
			(end -0.12065 0.2794)
			(stroke
				(width 0.1)
				(type default)
			)
			(layer "F.Fab")
		)
		(fp_line
			(start 0.120396 0.3048)
			(end 0.120396 0.2794)
			(stroke
				(width 0.1)
				(type default)
			)
			(layer "F.Fab")
		)
		(fp_line
			(start 0.12065 -0.3048)
			(end 0.67945 -0.3048)
			(stroke
				(width 0.1)
				(type default)
			)
			(layer "F.Fab")
		)
		(fp_line
			(start 0.12065 -0.2794)
			(end 0.12065 -0.3048)
			(stroke
				(width 0.1)
				(type default)
			)
			(layer "F.Fab")
		)
		(fp_line
			(start 0.67945 -0.3048)
			(end 0.67945 0.3048)
			(stroke
				(width 0.1)
				(type default)
			)
			(layer "F.Fab")
		)
		(fp_line
			(start 0.67945 0.3048)
			(end 0.120396 0.3048)
			(stroke
				(width 0.1)
				(type default)
			)
			(layer "F.Fab")
		)
		(pad "1" smd circle
			(at -0.40005 0)
			(size 0 0)
			(layers "F.Cu" "F.Mask" "F.Paste")
			(net "HP_LVC3_OCP_V3_2_PWRGD_R2")
		)
		(pad "2" smd circle
			(at 0.40005 0)
			(size 0 0)
			(layers "F.Cu" "F.Mask" "F.Paste")
			(net "OCP_V3_2_P3V3_R3_PWRGD")
		)
	)
)
